(kicad_pcb
	(version 20221018)
	(generator pcbnew)
	(general
    (thickness 1.62)
  )
	(paper "A4")
	(title_block
    (title "ECP5 - Datacenter Secure Control Module (DC-SCM)")
    (date "2024-07-01")
    (rev "1.2.1")
		(comment 9 "footprints 401-409 of 506")
	)
	(layers
    (0 "F.Cu" signal)
    (1 "In1.Cu" power)
    (2 "In2.Cu" signal)
    (3 "In3.Cu" power)
    (4 "In4.Cu" power)
    (5 "In5.Cu" signal)
    (6 "In6.Cu" power)
    (31 "B.Cu" signal)
    (32 "B.Adhes" user "B.Adhesive")
    (33 "F.Adhes" user "F.Adhesive")
    (34 "B.Paste" user)
    (35 "F.Paste" user)
    (36 "B.SilkS" user "B.Silkscreen")
    (37 "F.SilkS" user "F.Silkscreen")
    (38 "B.Mask" user)
    (39 "F.Mask" user)
    (40 "Dwgs.User" user "User.Drawings")
    (41 "Cmts.User" user "User.Comments")
    (42 "Eco1.User" user "User.Eco1")
    (43 "Eco2.User" user "User.Eco2")
    (44 "Edge.Cuts" user)
    (45 "Margin" user)
    (46 "B.CrtYd" user "B.Courtyard")
    (47 "F.CrtYd" user "F.Courtyard")
    (48 "B.Fab" user)
    (49 "F.Fab" user)
  )
	(footprint "antmicro-footprints:R_0402_1005Metric" (layer "B.Cu")
    (at 81.975 147.8 -90)
    (descr "Resistor SMD 0402")
    (tags "resistor SMD 0402")
    (property "Author" "Antmicro")
    (property "License" "Apache-2.0")
    (property "MPN" "CR0402-FX-1002GLF")
    (property "Manufacturer" "Bourns")
    (property "Public" "False")
    (property "Sheetfile" "rot.kicad_sch")
    (property "Sheetname" "RoT")
    (property "Tolerance" "1%")
    (property "Val" "10k")
    (property "ki_description" "SMD Chip Resistor, 10 kohm, ± 1%, 62.5 mW, 0402 [1005 Metric], Thick Film, General Purpose")
    (property "ki_keywords" "0402, SMT, RESISTOR, PASSIVE")
    (attr smd)
    (fp_text reference "R29" (at 2.75 0.825 -90) (layer "B.SilkS")
        (effects (font (size 0.7 0.7) (thickness 0.127)) (justify mirror))
    )
    (fp_text value "R_10k_0402" (at 0 -1.17 -90) (layer "B.Fab")
        (effects (font (size 1 1) (thickness 0.15)) (justify mirror))
    )
    (fp_text user "${REFERENCE}" (at 0 0 -90) (layer "B.Fab")
        (effects (font (size 0.25 0.25) (thickness 0.04)) (justify mirror))
    )
    (fp_text user "Author: Antmicro" (at -0.95 -4.169 90) (layer "B.Fab") hide
        (effects (font (size 0.7 0.7) (thickness 0.15)) (justify left bottom mirror))
    )
    (fp_text user "License: Apache-2.0" (at -0.95 -5.169 90) (layer "B.Fab") hide
        (effects (font (size 0.7 0.7) (thickness 0.15)) (justify left bottom mirror))
    )
    (fp_rect (start -0.925 0.47) (end 0.925 -0.47)
      (stroke (width 0.05) (type default)) (fill none) (layer "B.CrtYd"))
    (fp_rect (start -0.5 0.25) (end 0.5 -0.25)
      (stroke (width 0.15) (type solid)) (fill none) (layer "B.Fab"))
    (pad "1" smd roundrect (at -0.48 0 270) (size 0.59 0.64) (layers "B.Cu" "B.Paste" "B.Mask") (roundrect_rratio 0.25)
      (net 130 "QSPIB2_D0") (pintype "passive"))
    (pad "2" smd roundrect (at 0.48 0 270) (size 0.59 0.64) (layers "B.Cu" "B.Paste" "B.Mask") (roundrect_rratio 0.25)
      (net 2 "VCC3V3") (pintype "passive"))
  )
	(footprint "antmicro-footprints:R_0402_1005Metric" (layer "B.Cu")
    (at 70.725 138.835 -90)
    (descr "Resistor SMD 0402")
    (tags "resistor SMD 0402")
    (property "Author" "Antmicro")
    (property "License" "Apache-2.0")
    (property "MPN" "CR0402-FX-1002GLF")
    (property "Manufacturer" "Bourns")
    (property "Public" "False")
    (property "Sheetfile" "rot.kicad_sch")
    (property "Sheetname" "RoT")
    (property "Tolerance" "1%")
    (property "Val" "10k")
    (property "ki_description" "SMD Chip Resistor, 10 kohm, ± 1%, 62.5 mW, 0402 [1005 Metric], Thick Film, General Purpose")
    (property "ki_keywords" "0402, SMT, RESISTOR, PASSIVE")
    (attr smd)
    (fp_text reference "R31" (at 2.965 -0.334165 90) (layer "B.SilkS")
        (effects (font (size 0.7 0.7) (thickness 0.127)) (justify mirror))
    )
    (fp_text value "R_10k_0402" (at 0 -1.17 90) (layer "B.Fab")
        (effects (font (size 1 1) (thickness 0.15)) (justify mirror))
    )
    (fp_text user "License: Apache-2.0" (at -0.95 -5.169 90) (layer "B.Fab") hide
        (effects (font (size 0.7 0.7) (thickness 0.15)) (justify left bottom mirror))
    )
    (fp_text user "${REFERENCE}" (at 0 0 90) (layer "B.Fab")
        (effects (font (size 0.25 0.25) (thickness 0.04)) (justify mirror))
    )
    (fp_text user "Author: Antmicro" (at -0.95 -4.169 90) (layer "B.Fab") hide
        (effects (font (size 0.7 0.7) (thickness 0.15)) (justify left bottom mirror))
    )
    (fp_rect (start -0.925 0.47) (end 0.925 -0.47)
      (stroke (width 0.05) (type default)) (fill none) (layer "B.CrtYd"))
    (fp_rect (start -0.5 0.25) (end 0.5 -0.25)
      (stroke (width 0.15) (type solid)) (fill none) (layer "B.Fab"))
    (pad "1" smd roundrect (at -0.48 0 270) (size 0.59 0.64) (layers "B.Cu" "B.Paste" "B.Mask") (roundrect_rratio 0.25)
      (net 141 "QSPIA2_D0") (pintype "passive"))
    (pad "2" smd roundrect (at 0.48 0 270) (size 0.59 0.64) (layers "B.Cu" "B.Paste" "B.Mask") (roundrect_rratio 0.25)
      (net 2 "VCC3V3") (pintype "passive"))
  )
	(footprint "antmicro-footprints:R_0402_1005Metric" (layer "B.Cu")
    (at 76.975 147.8 -90)
    (descr "Resistor SMD 0402")
    (tags "resistor SMD 0402")
    (property "Author" "Antmicro")
    (property "License" "Apache-2.0")
    (property "MPN" "CR0402-FX-1002GLF")
    (property "Manufacturer" "Bourns")
    (property "Public" "False")
    (property "Sheetfile" "rot.kicad_sch")
    (property "Sheetname" "RoT")
    (property "Tolerance" "1%")
    (property "Val" "10k")
    (property "ki_description" "SMD Chip Resistor, 10 kohm, ± 1%, 62.5 mW, 0402 [1005 Metric], Thick Film, General Purpose")
    (property "ki_keywords" "0402, SMT, RESISTOR, PASSIVE")
    (attr smd)
    (fp_text reference "R33" (at 2.75 0.025 -90) (layer "B.SilkS")
        (effects (font (size 0.7 0.7) (thickness 0.127)) (justify mirror))
    )
    (fp_text value "R_10k_0402" (at 0 -1.17 -90) (layer "B.Fab")
        (effects (font (size 1 1) (thickness 0.15)) (justify mirror))
    )
    (fp_text user "${REFERENCE}" (at 0 0 -90) (layer "B.Fab")
        (effects (font (size 0.25 0.25) (thickness 0.04)) (justify mirror))
    )
    (fp_text user "Author: Antmicro" (at -0.95 -4.169 90) (layer "B.Fab") hide
        (effects (font (size 0.7 0.7) (thickness 0.15)) (justify left bottom mirror))
    )
    (fp_text user "License: Apache-2.0" (at -0.95 -5.169 90) (layer "B.Fab") hide
        (effects (font (size 0.7 0.7) (thickness 0.15)) (justify left bottom mirror))
    )
    (fp_rect (start -0.925 0.47) (end 0.925 -0.47)
      (stroke (width 0.05) (type default)) (fill none) (layer "B.CrtYd"))
    (fp_rect (start -0.5 0.25) (end 0.5 -0.25)
      (stroke (width 0.15) (type solid)) (fill none) (layer "B.Fab"))
    (pad "1" smd roundrect (at -0.48 0 270) (size 0.59 0.64) (layers "B.Cu" "B.Paste" "B.Mask") (roundrect_rratio 0.25)
      (net 132 "QSPIB2_D2") (pintype "passive"))
    (pad "2" smd roundrect (at 0.48 0 270) (size 0.59 0.64) (layers "B.Cu" "B.Paste" "B.Mask") (roundrect_rratio 0.25)
      (net 2 "VCC3V3") (pintype "passive"))
  )
	(footprint "antmicro-footprints:R_0402_1005Metric" (layer "B.Cu")
    (at 65.725 138.85 -90)
    (descr "Resistor SMD 0402")
    (tags "resistor SMD 0402")
    (property "Author" "Antmicro")
    (property "License" "Apache-2.0")
    (property "MPN" "CR0402-FX-1002GLF")
    (property "Manufacturer" "Bourns")
    (property "Public" "False")
    (property "Sheetfile" "rot.kicad_sch")
    (property "Sheetname" "RoT")
    (property "Tolerance" "1%")
    (property "Val" "10k")
    (property "ki_description" "SMD Chip Resistor, 10 kohm, ± 1%, 62.5 mW, 0402 [1005 Metric], Thick Film, General Purpose")
    (property "ki_keywords" "0402, SMT, RESISTOR, PASSIVE")
    (attr smd)
    (fp_text reference "R35" (at 2.95 0.12 90) (layer "B.SilkS")
        (effects (font (size 0.7 0.7) (thickness 0.127)) (justify mirror))
    )
    (fp_text value "R_10k_0402" (at 0 -1.17 90) (layer "B.Fab")
        (effects (font (size 1 1) (thickness 0.15)) (justify mirror))
    )
    (fp_text user "${REFERENCE}" (at 0 0 90) (layer "B.Fab")
        (effects (font (size 0.25 0.25) (thickness 0.04)) (justify mirror))
    )
    (fp_text user "Author: Antmicro" (at -0.95 -4.169 90) (layer "B.Fab") hide
        (effects (font (size 0.7 0.7) (thickness 0.15)) (justify left bottom mirror))
    )
    (fp_text user "License: Apache-2.0" (at -0.95 -5.169 90) (layer "B.Fab") hide
        (effects (font (size 0.7 0.7) (thickness 0.15)) (justify left bottom mirror))
    )
    (fp_rect (start -0.925 0.47) (end 0.925 -0.47)
      (stroke (width 0.05) (type default)) (fill none) (layer "B.CrtYd"))
    (fp_rect (start -0.5 0.25) (end 0.5 -0.25)
      (stroke (width 0.15) (type solid)) (fill none) (layer "B.Fab"))
    (pad "1" smd roundrect (at -0.48 0 270) (size 0.59 0.64) (layers "B.Cu" "B.Paste" "B.Mask") (roundrect_rratio 0.25)
      (net 143 "QSPIA2_D2") (pintype "passive"))
    (pad "2" smd roundrect (at 0.48 0 270) (size 0.59 0.64) (layers "B.Cu" "B.Paste" "B.Mask") (roundrect_rratio 0.25)
      (net 2 "VCC3V3") (pintype "passive"))
  )
	(footprint "antmicro-footprints:R_0402_1005Metric" (layer "B.Cu")
    (at 79.975 147.8 -90)
    (descr "Resistor SMD 0402")
    (tags "resistor SMD 0402")
    (property "Author" "Antmicro")
    (property "License" "Apache-2.0")
    (property "MPN" "CR0402-FX-1002GLF")
    (property "Manufacturer" "Bourns")
    (property "Public" "False")
    (property "Sheetfile" "rot.kicad_sch")
    (property "Sheetname" "RoT")
    (property "Tolerance" "1%")
    (property "Val" "10k")
    (property "ki_description" "SMD Chip Resistor, 10 kohm, ± 1%, 62.5 mW, 0402 [1005 Metric], Thick Film, General Purpose")
    (property "ki_keywords" "0402, SMT, RESISTOR, PASSIVE")
    (attr smd)
    (fp_text reference "R37" (at 2.75 0.925 -90) (layer "B.SilkS")
        (effects (font (size 0.7 0.7) (thickness 0.127)) (justify mirror))
    )
    (fp_text value "R_10k_0402" (at 0 -1.17 -90) (layer "B.Fab")
        (effects (font (size 1 1) (thickness 0.15)) (justify mirror))
    )
    (fp_text user "Author: Antmicro" (at -0.95 -4.169 90) (layer "B.Fab") hide
        (effects (font (size 0.7 0.7) (thickness 0.15)) (justify left bottom mirror))
    )
    (fp_text user "License: Apache-2.0" (at -0.95 -5.169 90) (layer "B.Fab") hide
        (effects (font (size 0.7 0.7) (thickness 0.15)) (justify left bottom mirror))
    )
    (fp_text user "${REFERENCE}" (at 0 0 -90) (layer "B.Fab")
        (effects (font (size 0.25 0.25) (thickness 0.04)) (justify mirror))
    )
    (fp_rect (start -0.925 0.47) (end 0.925 -0.47)
      (stroke (width 0.05) (type default)) (fill none) (layer "B.CrtYd"))
    (fp_rect (start -0.5 0.25) (end 0.5 -0.25)
      (stroke (width 0.15) (type solid)) (fill none) (layer "B.Fab"))
    (pad "1" smd roundrect (at -0.48 0 270) (size 0.59 0.64) (layers "B.Cu" "B.Paste" "B.Mask") (roundrect_rratio 0.25)
      (net 133 "QSPIB2_D3") (pintype "passive"))
    (pad "2" smd roundrect (at 0.48 0 270) (size 0.59 0.64) (layers "B.Cu" "B.Paste" "B.Mask") (roundrect_rratio 0.25)
      (net 2 "VCC3V3") (pintype "passive"))
  )
	(footprint "antmicro-footprints:R_0402_1005Metric" (layer "B.Cu")
    (at 68.725 138.85 -90)
    (descr "Resistor SMD 0402")
    (tags "resistor SMD 0402")
    (property "Author" "Antmicro")
    (property "License" "Apache-2.0")
    (property "MPN" "CR0402-FX-1002GLF")
    (property "Manufacturer" "Bourns")
    (property "Public" "False")
    (property "Sheetfile" "rot.kicad_sch")
    (property "Sheetname" "RoT")
    (property "Tolerance" "1%")
    (property "Val" "10k")
    (property "ki_description" "SMD Chip Resistor, 10 kohm, ± 1%, 62.5 mW, 0402 [1005 Metric], Thick Film, General Purpose")
    (property "ki_keywords" "0402, SMT, RESISTOR, PASSIVE")
    (attr smd)
    (fp_text reference "R39" (at 2.95 -0.152499 90) (layer "B.SilkS")
        (effects (font (size 0.7 0.7) (thickness 0.127)) (justify mirror))
    )
    (fp_text value "R_10k_0402" (at 0 -1.17 90) (layer "B.Fab")
        (effects (font (size 1 1) (thickness 0.15)) (justify mirror))
    )
    (fp_text user "Author: Antmicro" (at -0.95 -4.169 90) (layer "B.Fab") hide
        (effects (font (size 0.7 0.7) (thickness 0.15)) (justify left bottom mirror))
    )
    (fp_text user "${REFERENCE}" (at 0 0 90) (layer "B.Fab")
        (effects (font (size 0.25 0.25) (thickness 0.04)) (justify mirror))
    )
    (fp_text user "License: Apache-2.0" (at -0.95 -5.169 90) (layer "B.Fab") hide
        (effects (font (size 0.7 0.7) (thickness 0.15)) (justify left bottom mirror))
    )
    (fp_rect (start -0.925 0.47) (end 0.925 -0.47)
      (stroke (width 0.05) (type default)) (fill none) (layer "B.CrtYd"))
    (fp_rect (start -0.5 0.25) (end 0.5 -0.25)
      (stroke (width 0.15) (type solid)) (fill none) (layer "B.Fab"))
    (pad "1" smd roundrect (at -0.48 0 270) (size 0.59 0.64) (layers "B.Cu" "B.Paste" "B.Mask") (roundrect_rratio 0.25)
      (net 144 "QSPIA2_D3") (pintype "passive"))
    (pad "2" smd roundrect (at 0.48 0 270) (size 0.59 0.64) (layers "B.Cu" "B.Paste" "B.Mask") (roundrect_rratio 0.25)
      (net 2 "VCC3V3") (pintype "passive"))
  )
	(footprint "antmicro-footprints:R_0402_1005Metric" (layer "B.Cu")
    (at 77.975 147.8 -90)
    (descr "Resistor SMD 0402")
    (tags "resistor SMD 0402")
    (property "Author" "Antmicro")
    (property "License" "Apache-2.0")
    (property "MPN" "CR0402-FX-1002GLF")
    (property "Manufacturer" "Bourns")
    (property "Public" "False")
    (property "Sheetfile" "rot.kicad_sch")
    (property "Sheetname" "RoT")
    (property "Tolerance" "1%")
    (property "Val" "10k")
    (property "ki_description" "SMD Chip Resistor, 10 kohm, ± 1%, 62.5 mW, 0402 [1005 Metric], Thick Film, General Purpose")
    (property "ki_keywords" "0402, SMT, RESISTOR, PASSIVE")
    (attr smd)
    (fp_text reference "R41" (at 2.75 -0.025 -90) (layer "B.SilkS")
        (effects (font (size 0.7 0.7) (thickness 0.127)) (justify mirror))
    )
    (fp_text value "R_10k_0402" (at 0 -1.17 -90) (layer "B.Fab")
        (effects (font (size 1 1) (thickness 0.15)) (justify mirror))
    )
    (fp_text user "License: Apache-2.0" (at -0.95 -5.169 90) (layer "B.Fab") hide
        (effects (font (size 0.7 0.7) (thickness 0.15)) (justify left bottom mirror))
    )
    (fp_text user "${REFERENCE}" (at 0 0 -90) (layer "B.Fab")
        (effects (font (size 0.25 0.25) (thickness 0.04)) (justify mirror))
    )
    (fp_text user "Author: Antmicro" (at -0.95 -4.169 90) (layer "B.Fab") hide
        (effects (font (size 0.7 0.7) (thickness 0.15)) (justify left bottom mirror))
    )
    (fp_rect (start -0.925 0.47) (end 0.925 -0.47)
      (stroke (width 0.05) (type default)) (fill none) (layer "B.CrtYd"))
    (fp_rect (start -0.5 0.25) (end 0.5 -0.25)
      (stroke (width 0.15) (type solid)) (fill none) (layer "B.Fab"))
    (pad "1" smd roundrect (at -0.48 0 270) (size 0.59 0.64) (layers "B.Cu" "B.Paste" "B.Mask") (roundrect_rratio 0.25)
      (net 131 "QSPIB2_D1") (pintype "passive"))
    (pad "2" smd roundrect (at 0.48 0 270) (size 0.59 0.64) (layers "B.Cu" "B.Paste" "B.Mask") (roundrect_rratio 0.25)
      (net 2 "VCC3V3") (pintype "passive"))
  )
	(footprint "antmicro-footprints:R_0402_1005Metric" (layer "B.Cu")
    (at 66.725 138.85 -90)
    (descr "Resistor SMD 0402")
    (tags "resistor SMD 0402")
    (property "Author" "Antmicro")
    (property "License" "Apache-2.0")
    (property "MPN" "CR0402-FX-1002GLF")
    (property "Manufacturer" "Bourns")
    (property "Public" "False")
    (property "Sheetfile" "rot.kicad_sch")
    (property "Sheetname" "RoT")
    (property "Tolerance" "1%")
    (property "Val" "10k")
    (property "ki_description" "SMD Chip Resistor, 10 kohm, ± 1%, 62.5 mW, 0402 [1005 Metric], Thick Film, General Purpose")
    (property "ki_keywords" "0402, SMT, RESISTOR, PASSIVE")
    (attr smd)
    (fp_text reference "R43" (at 2.95 0.029167 90) (layer "B.SilkS")
        (effects (font (size 0.7 0.7) (thickness 0.127)) (justify mirror))
    )
    (fp_text value "R_10k_0402" (at 0 -1.17 90) (layer "B.Fab")
        (effects (font (size 1 1) (thickness 0.15)) (justify mirror))
    )
    (fp_text user "${REFERENCE}" (at 0 0 90) (layer "B.Fab")
        (effects (font (size 0.25 0.25) (thickness 0.04)) (justify mirror))
    )
    (fp_text user "Author: Antmicro" (at -0.95 -4.169 90) (layer "B.Fab") hide
        (effects (font (size 0.7 0.7) (thickness 0.15)) (justify left bottom mirror))
    )
    (fp_text user "License: Apache-2.0" (at -0.95 -5.169 90) (layer "B.Fab") hide
        (effects (font (size 0.7 0.7) (thickness 0.15)) (justify left bottom mirror))
    )
    (fp_rect (start -0.925 0.47) (end 0.925 -0.47)
      (stroke (width 0.05) (type default)) (fill none) (layer "B.CrtYd"))
    (fp_rect (start -0.5 0.25) (end 0.5 -0.25)
      (stroke (width 0.15) (type solid)) (fill none) (layer "B.Fab"))
    (pad "1" smd roundrect (at -0.48 0 270) (size 0.59 0.64) (layers "B.Cu" "B.Paste" "B.Mask") (roundrect_rratio 0.25)
      (net 142 "QSPIA2_D1") (pintype "passive"))
    (pad "2" smd roundrect (at 0.48 0 270) (size 0.59 0.64) (layers "B.Cu" "B.Paste" "B.Mask") (roundrect_rratio 0.25)
      (net 2 "VCC3V3") (pintype "passive"))
  )
	(footprint "antmicro-footprints:C_0402_1005Metric" (layer "B.Cu")
    (at 71.9 138.815 -90)
    (descr "Capacitor SMD 0402")
    (tags "capacitor SMD 0402")
    (property "Author" "Antmicro")
    (property "Dielectric" "")
    (property "License" "Apache-2.0")
    (property "MPN" "C1005X5R1E474M050BB")
    (property "Manufacturer" "TDK")
    (property "Public" "False")
    (property "Sheetfile" "rot.kicad_sch")
    (property "Sheetname" "RoT")
    (property "Val" "470n")
    (property "Voltage" "")
    (property "ki_description" "SMD Multilayer Ceramic Capacitor, 0.47 µF, 25 V, 0402 [1005 Metric], ± 20%, X5R, C")
    (property "ki_keywords" "0402, SMT, CAPACITOR, PASSIVE, CERAMIC, MLCC")
    (attr smd)
    (fp_text reference "C46" (at -2.985 0.249998 90) (layer "B.SilkS")
        (effects (font (size 0.7 0.7) (thickness 0.127)) (justify mirror))
    )
    (fp_text value "C_470n_0402" (at 0 -1.17 90) (layer "B.Fab")
        (effects (font (size 1 1) (thickness 0.15)) (justify mirror))
    )
    (fp_text user "License: Apache-2.0" (at -0.939 -5.799 90) (layer "B.Fab") hide
        (effects (font (size 0.7 0.7) (thickness 0.15)) (justify left bottom mirror))
    )
    (fp_text user "${REFERENCE}" (at 0 0 90) (layer "B.Fab")
        (effects (font (size 0.25 0.25) (thickness 0.04)) (justify mirror))
    )
    (fp_text user "Author: Antmicro" (at -0.939 -3.399 90) (layer "B.Fab") hide
        (effects (font (size 0.7 0.7) (thickness 0.15)) (justify left bottom mirror))
    )
    (fp_rect (start -0.925 0.47) (end 0.925 -0.47)
      (stroke (width 0.05) (type default)) (fill none) (layer "B.CrtYd"))
    (fp_line (start -0.494 -0.248) (end -0.494 0.25)
      (stroke (width 0.15) (type solid)) (layer "B.Fab"))
    (fp_line (start -0.494 0.25) (end 0.504 0.25)
      (stroke (width 0.15) (type solid)) (layer "B.Fab"))
    (fp_line (start 0.504 -0.248) (end -0.494 -0.248)
      (stroke (width 0.15) (type solid)) (layer "B.Fab"))
    (fp_line (start 0.504 0.25) (end 0.504 -0.248)
      (stroke (width 0.15) (type solid)) (layer "B.Fab"))
    (pad "1" smd roundrect (at -0.48 0 270) (size 0.59 0.64) (layers "B.Cu" "B.Paste" "B.Mask") (roundrect_rratio 0.25)
      (net 1 "GND") (pintype "passive"))
    (pad "2" smd roundrect (at 0.48 0 270) (size 0.59 0.64) (layers "B.Cu" "B.Paste" "B.Mask") (roundrect_rratio 0.25)
      (net 2 "VCC3V3") (pintype "passive"))
  )
)
